# T6G (Grand Teton) — schematic netlist excerpt (pin names and nets, part order shuffled) for the footprints in the layout excerpt that follows; sources: Cadence DE-HDL packaged netlist, KiCad conversion of 04192023_DAF0TMB3IC0_F0TG_MB_C_brd_V02_OCP.brd

C708  Q_CAP_DIFFBUS  DIFF BUS_0.22UF 6.3V 20% X6S  pkg C0201  page 67 : \1\ = P5E_CPU1_G1_TX_C_DN<0> ; \2\ = P5E_CPU1_G1_TX_DN<0>
PC1789  Q_CAP  0.1UF 25V 10% X7R  pkg 0402  page 267 : A = P12V_AUX ; B = GND
R2950  Q_RES  1K 1% CHIP  pkg 0402LF  page 240 : A = P3V3_AUX ; B = FM_PDB_BUF_EN_R1_N

(kicad_pcb
	(version 20260206)
	(generator "pcbnew")
	(generator_version "10.0")
	(general
		(thickness 1.6)
		(legacy_teardrops no)
	)
	(paper "A4")
	(title_block
		(title "04192023_DAF0TMB3IC0_F0TG_MB_C_brd_V02_OCP.brd")
		(comment 1 "Grand Teton / footprints 1836-1838 of 8354")
	)
	(layers
		(0 "F.Cu" signal "TOP")
		(4 "In1.Cu" signal "GND")
		(6 "In2.Cu" signal "IN1")
		(8 "In3.Cu" signal "GND1")
		(10 "In4.Cu" signal "IN2")
		(12 "In5.Cu" signal "GND2")
		(14 "In6.Cu" signal "IN3")
		(16 "In7.Cu" signal "GND3")
		(18 "In8.Cu" signal "VCC")
		(20 "In9.Cu" signal "VCC1")
		(22 "In10.Cu" signal "GND4")
		(24 "In11.Cu" signal "IN4")
		(26 "In12.Cu" signal "GND5")
		(28 "In13.Cu" signal "IN5")
		(30 "In14.Cu" signal "GND6")
		(32 "In15.Cu" signal "IN6")
		(34 "In16.Cu" signal "GND7")
		(2 "B.Cu" signal "BOTTOM")
		(9 "F.Adhes" user "F.Adhesive")
		(11 "B.Adhes" user "B.Adhesive")
		(13 "F.Paste" user "Package Geometry/Pastemask Top")
		(15 "B.Paste" user "Package Geometry/Pastemask Bottom")
		(5 "F.SilkS" user "Ref Des/Silkscreen Top")
		(7 "B.SilkS" user "Ref Des/Silkscreen Bottom")
		(1 "F.Mask" user "Board Geometry/Soldermask Top")
		(3 "B.Mask" user "Board Geometry/Soldermask Bottom")
		(17 "Dwgs.User" user "User.Drawings")
		(19 "Cmts.User" user "User.Comments")
		(21 "Eco1.User" user "User.Eco1")
		(23 "Eco2.User" user "User.Eco2")
		(25 "Edge.Cuts" user "Board Geometry/Outline")
		(27 "Margin" user)
		(31 "F.CrtYd" user "Package Geometry/Place Bound Top")
		(29 "B.CrtYd" user "Package Geometry/Place Bound Bottom")
		(35 "F.Fab" user "Ref Des/Assembly Top")
		(33 "B.Fab" user "Ref Des/Assembly Bottom")
	)
	(footprint ""
		(layer "F.Cu")
		(at 200.476358 -387.560566 90)
		(property "Reference" "PC1789"
			(at 0 0 90)
			(layer "F.SilkS")
			(hide yes)
			(effects
				(font
					(size 1.27 1.27)
				)
			)
		)
		(property "Value" ""
			(at 0 0 90)
			(layer "F.Fab")
			(effects
				(font
					(size 1.27 1.27)
				)
			)
		)
		(duplicate_pad_numbers_are_jumpers no)
		(fp_line
			(start 0.7874 -0.4064)
			(end 0.7874 0.4064)
			(stroke
				(width 0.1524)
				(type default)
			)
			(layer "F.SilkS")
		)
		(fp_line
			(start -0.7874 -0.4064)
			(end 0.7874 -0.4064)
			(stroke
				(width 0.1524)
				(type default)
			)
			(layer "F.SilkS")
		)
		(fp_line
			(start 0.7874 0.4064)
			(end -0.7874 0.4064)
			(stroke
				(width 0.1524)
				(type default)
			)
			(layer "F.SilkS")
		)
		(fp_line
			(start -0.7874 0.4064)
			(end -0.7874 -0.4064)
			(stroke
				(width 0.1524)
				(type default)
			)
			(layer "F.SilkS")
		)
		(fp_line
			(start -0.12065 -0.305054)
			(end -0.12065 -0.2794)
			(stroke
				(width 0.1)
				(type default)
			)
			(layer "F.Fab")
		)
		(fp_line
			(start -0.67945 -0.305054)
			(end -0.12065 -0.305054)
			(stroke
				(width 0.1)
				(type default)
			)
			(layer "F.Fab")
		)
		(fp_line
			(start 0.67945 -0.3048)
			(end 0.67945 0.3048)
			(stroke
				(width 0.1)
				(type default)
			)
			(layer "F.Fab")
		)
		(fp_line
			(start 0.12065 -0.3048)
			(end 0.67945 -0.3048)
			(stroke
				(width 0.1)
				(type default)
			)
			(layer "F.Fab")
		)
		(fp_line
			(start 0.12065 -0.2794)
			(end 0.12065 -0.3048)
			(stroke
				(width 0.1)
				(type default)
			)
			(layer "F.Fab")
		)
		(fp_line
			(start -0.12065 -0.2794)
			(end 0.12065 -0.2794)
			(stroke
				(width 0.1)
				(type default)
			)
			(layer "F.Fab")
		)
		(fp_line
			(start 0.120396 0.2794)
			(end -0.12065 0.2794)
			(stroke
				(width 0.1)
				(type default)
			)
			(layer "F.Fab")
		)
		(fp_line
			(start -0.12065 0.2794)
			(end -0.12065 0.3048)
			(stroke
				(width 0.1)
				(type default)
			)
			(layer "F.Fab")
		)
		(fp_line
			(start 0.67945 0.3048)
			(end 0.120396 0.3048)
			(stroke
				(width 0.1)
				(type default)
			)
			(layer "F.Fab")
		)
		(fp_line
			(start 0.120396 0.3048)
			(end 0.120396 0.2794)
			(stroke
				(width 0.1)
				(type default)
			)
			(layer "F.Fab")
		)
		(fp_line
			(start -0.12065 0.3048)
			(end -0.67945 0.3048)
			(stroke
				(width 0.1)
				(type default)
			)
			(layer "F.Fab")
		)
		(fp_line
			(start -0.67945 0.3048)
			(end -0.67945 -0.305054)
			(stroke
				(width 0.1)
				(type default)
			)
			(layer "F.Fab")
		)
		(pad "1" smd circle
			(at -0.40005 0 90)
			(size 0 0)
			(layers "F.Cu" "F.Mask" "F.Paste")
			(net "P12V_AUX")
		)
		(pad "2" smd circle
			(at 0.40005 0 90)
			(size 0 0)
			(layers "F.Cu" "F.Mask" "F.Paste")
			(net "GND")
		)
	)
	(footprint ""
		(layer "F.Cu")
		(at 57.75833 -17.623536 90)
		(property "Reference" "C708"
			(at 0 0 90)
			(layer "F.SilkS")
			(hide yes)
			(effects
				(font
					(size 1.27 1.27)
				)
			)
		)
		(property "Value" ""
			(at 0 0 90)
			(layer "F.Fab")
			(effects
				(font
					(size 1.27 1.27)
				)
			)
		)
		(duplicate_pad_numbers_are_jumpers no)
		(fp_line
			(start 0.299974 -0.150114)
			(end 0.299974 0.150114)
			(stroke
				(width 0.1)
				(type default)
			)
			(layer "F.Fab")
		)
		(fp_line
			(start -0.299974 -0.150114)
			(end 0.299974 -0.150114)
			(stroke
				(width 0.1)
				(type default)
			)
			(layer "F.Fab")
		)
		(fp_line
			(start 0.299974 0.150114)
			(end -0.299974 0.150114)
			(stroke
				(width 0.1)
				(type default)
			)
			(layer "F.Fab")
		)
		(fp_line
			(start -0.299974 0.150114)
			(end -0.299974 -0.150114)
			(stroke
				(width 0.1)
				(type default)
			)
			(layer "F.Fab")
		)
		(pad "1" smd rect
			(at -0.2667 0 90)
			(size 0.3048 0.381)
			(layers "F.Cu" "F.Mask" "F.Paste")
			(net "P5E_CPU1_G1_TX_C_DN<0>")
		)
		(pad "2" smd rect
			(at 0.2667 0 90)
			(size 0.3048 0.381)
			(layers "F.Cu" "F.Mask" "F.Paste")
			(net "P5E_CPU1_G1_TX_DN<0>")
		)
	)
	(footprint ""
		(layer "F.Cu")
		(at 191.055498 -428.496476 90)
		(property "Reference" "R2950"
			(at 0 0 90)
			(layer "F.SilkS")
			(hide yes)
			(effects
				(font
					(size 1.27 1.27)
				)
			)
		)
		(property "Value" ""
			(at 0 0 90)
			(layer "F.Fab")
			(effects
				(font
					(size 1.27 1.27)
				)
			)
		)
		(duplicate_pad_numbers_are_jumpers no)
		(fp_line
			(start 0.7874 -0.4064)
			(end 0.7874 0.4064)
			(stroke
				(width 0.1524)
				(type default)
			)
			(layer "F.SilkS")
		)
		(fp_line
			(start -0.7874 -0.4064)
			(end 0.7874 -0.4064)
			(stroke
				(width 0.1524)
				(type default)
			)
			(layer "F.SilkS")
		)
		(fp_line
			(start 0.7874 0.4064)
			(end -0.7874 0.4064)
			(stroke
				(width 0.1524)
				(type default)
			)
			(layer "F.SilkS")
		)
		(fp_line
			(start -0.7874 0.4064)
			(end -0.7874 -0.4064)
			(stroke
				(width 0.1524)
				(type default)
			)
			(layer "F.SilkS")
		)
		(fp_line
			(start -0.12065 -0.305054)
			(end -0.12065 -0.2794)
			(stroke
				(width 0.1)
				(type default)
			)
			(layer "F.Fab")
		)
		(fp_line
			(start -0.67945 -0.305054)
			(end -0.12065 -0.305054)
			(stroke
				(width 0.1)
				(type default)
			)
			(layer "F.Fab")
		)
		(fp_line
			(start 0.67945 -0.3048)
			(end 0.67945 0.3048)
			(stroke
				(width 0.1)
				(type default)
			)
			(layer "F.Fab")
		)
		(fp_line
			(start 0.12065 -0.3048)
			(end 0.67945 -0.3048)
			(stroke
				(width 0.1)
				(type default)
			)
			(layer "F.Fab")
		)
		(fp_line
			(start 0.12065 -0.2794)
			(end 0.12065 -0.3048)
			(stroke
				(width 0.1)
				(type default)
			)
			(layer "F.Fab")
		)
		(fp_line
			(start -0.12065 -0.2794)
			(end 0.12065 -0.2794)
			(stroke
				(width 0.1)
				(type default)
			)
			(layer "F.Fab")
		)
		(fp_line
			(start 0.120396 0.2794)
			(end -0.12065 0.2794)
			(stroke
				(width 0.1)
				(type default)
			)
			(layer "F.Fab")
		)
		(fp_line
			(start -0.12065 0.2794)
			(end -0.12065 0.3048)
			(stroke
				(width 0.1)
				(type default)
			)
			(layer "F.Fab")
		)
		(fp_line
			(start 0.67945 0.3048)
			(end 0.120396 0.3048)
			(stroke
				(width 0.1)
				(type default)
			)
			(layer "F.Fab")
		)
		(fp_line
			(start 0.120396 0.3048)
			(end 0.120396 0.2794)
			(stroke
				(width 0.1)
				(type default)
			)
			(layer "F.Fab")
		)
		(fp_line
			(start -0.12065 0.3048)
			(end -0.67945 0.3048)
			(stroke
				(width 0.1)
				(type default)
			)
			(layer "F.Fab")
		)
		(fp_line
			(start -0.67945 0.3048)
			(end -0.67945 -0.305054)
			(stroke
				(width 0.1)
				(type default)
			)
			(layer "F.Fab")
		)
		(pad "1" smd circle
			(at -0.40005 0 90)
			(size 0 0)
			(layers "F.Cu" "F.Mask" "F.Paste")
			(net "P3V3_AUX")
		)
		(pad "2" smd circle
			(at 0.40005 0 90)
			(size 0 0)
			(layers "F.Cu" "F.Mask" "F.Paste")
			(net "FM_PDB_BUF_EN_R1_N")
		)
	)
)
